#ISCELL
  pure_quanta quanta_title_block_c *
  *
#ISCELL
  standard offpage *
  page327_i1
#ISCELL
  standard offpage *
  page327_i10
#ISCELL
  standard offpage *
  page327_i11
#ISCELL
  standard offpage *
  page327_i12
#ISCELL
  standard offpage *
  page327_i13
#ISCELL
  standard offpage *
  page327_i14
#ISCELL
  standard offpage *
  page327_i15
#ISCELL
  standard offpage *
  page327_i16
#ISCELL
  standard offpage *
  page327_i17
#ISCELL
  pure_quanta_power universal_gnd *
  page327_i18
#CELL
  pure_quanta conn112_10137002101lf *
  page327_i19
#ISCELL
  standard offpage *
  page327_i2
#ISCELL
  standard offpage *
  page327_i20
#ISCELL
  standard offpage *
  page327_i21
#ISCELL
  standard offpage *
  page327_i22
#ISCELL
  standard offpage *
  page327_i23
#ISCELL
  standard offpage *
  page327_i24
#ISCELL
  standard offpage *
  page327_i25
#ISCELL
  standard offpage *
  page327_i26
#ISCELL
  standard offpage *
  page327_i27
#ISCELL
  standard offpage *
  page327_i28
#ISCELL
  standard offpage *
  page327_i29
#ISCELL
  standard offpage *
  page327_i3
#ISCELL
  standard offpage *
  page327_i30
#ISCELL
  standard offpage *
  page327_i31
#ISCELL
  standard offpage *
  page327_i32
#ISCELL
  standard offpage *
  page327_i33
#ISCELL
  standard offpage *
  page327_i34
#ISCELL
  standard offpage *
  page327_i35
#ISCELL
  standard offpage *
  page327_i36
#ISCELL
  standard offpage *
  page327_i37
#ISCELL
  standard offpage *
  page327_i38
#ISCELL
  standard offpage *
  page327_i39
#ISCELL
  standard offpage *
  page327_i4
#ISCELL
  standard offpage *
  page327_i40
#ISCELL
  standard offpage *
  page327_i41
#ISCELL
  standard offpage *
  page327_i42
#ISCELL
  standard offpage *
  page327_i43
#ISCELL
  standard offpage *
  page327_i44
#ISCELL
  standard offpage *
  page327_i45
#ISCELL
  standard offpage *
  page327_i46
#ISCELL
  standard offpage *
  page327_i47
#ISCELL
  standard offpage *
  page327_i48
#ISCELL
  standard offpage *
  page327_i49
#ISCELL
  standard offpage *
  page327_i5
#ISCELL
  standard offpage *
  page327_i50
#ISCELL
  standard offpage *
  page327_i51
#ISCELL
  standard offpage *
  page327_i52
#ISCELL
  standard offpage *
  page327_i53
#ISCELL
  standard offpage *
  page327_i54
#ISCELL
  pure_quanta_power universal_gnd *
  page327_i55
#ISCELL
  standard offpage *
  page327_i56
#ISCELL
  standard offpage *
  page327_i57
#ISCELL
  standard offpage *
  page327_i58
#ISCELL
  standard offpage *
  page327_i59
#ISCELL
  standard offpage *
  page327_i6
#ISCELL
  standard offpage *
  page327_i60
#ISCELL
  standard offpage *
  page327_i61
#ISCELL
  standard offpage *
  page327_i62
#ISCELL
  standard offpage *
  page327_i63
#ISCELL
  standard offpage *
  page327_i64
#ISCELL
  standard offpage *
  page327_i65
#ISCELL
  standard offpage *
  page327_i66
#ISCELL
  standard offpage *
  page327_i67
#ISCELL
  standard offpage *
  page327_i68
#ISCELL
  standard offpage *
  page327_i69
#ISCELL
  standard offpage *
  page327_i7
#ISCELL
  standard offpage *
  page327_i70
#ISCELL
  standard offpage *
  page327_i71
#ISCELL
  standard offpage *
  page327_i72
#ISCELL
  standard offpage *
  page327_i73
#CELL
  pure_quanta conn112_10137002101lf *
  page327_i74
#ISCELL
  standard offpage *
  page327_i75
#ISCELL
  standard offpage *
  page327_i8
#ISCELL
  standard offpage *
  page327_i9
